# S9S_MB_2U (Grand Teton) — schematic netlist excerpt (pin names and nets, part order shuffled) for the footprints in the layout excerpt that follows; sources: Cadence DE-HDL packaged netlist, KiCad conversion of 03242023_DA0F0TMBIJ0_F0T_Motherboard_J_brd_V01_OCP.brd

C170  Q_CAP_DIFFBUS  DIFF BUS_0.22UF 6.3V 20% X6S  pkg C0201  page 178 : \1\ = DMI_CPU0_PCH_RX_C_DP<0> ; \2\ = DMI_CPU0_PCH_RX_DP<0>
R1675  Q_RES  2.49K 1% CHIP  pkg 0402LF  page 182 : A = FM_PCIE_EV_BIF_EN ; B = P3V3_AUX
R257  Q_RES  240 1% EMPTY  pkg 0402LF  page 120 : A = PVNN_TERM_CPU1 ; B = FM_S3M_CPU1_LVC1_GPIO_4

(kicad_pcb
	(version 20260206)
	(generator "pcbnew")
	(generator_version "10.0")
	(general
		(thickness 1.6)
		(legacy_teardrops no)
	)
	(paper "A4")
	(title_block
		(title "03242023_DA0F0TMBIJ0_F0T_Motherboard_J_brd_V01_OCP.brd")
		(comment 1 "Grand Teton / footprints 4275-4277 of 6105")
	)
	(layers
		(0 "F.Cu" signal "TOP")
		(4 "In1.Cu" signal "GND")
		(6 "In2.Cu" signal "IN1")
		(8 "In3.Cu" signal "GND1")
		(10 "In4.Cu" signal "IN2")
		(12 "In5.Cu" signal "GND2")
		(14 "In6.Cu" signal "IN3")
		(16 "In7.Cu" signal "GND3")
		(18 "In8.Cu" signal "VCC")
		(20 "In9.Cu" signal "VCC1")
		(22 "In10.Cu" signal "GND4")
		(24 "In11.Cu" signal "IN4")
		(26 "In12.Cu" signal "GND5")
		(28 "In13.Cu" signal "IN5")
		(30 "In14.Cu" signal "GND6")
		(32 "In15.Cu" signal "IN6")
		(34 "In16.Cu" signal "GND7")
		(2 "B.Cu" signal "BOTTOM")
		(9 "F.Adhes" user "F.Adhesive")
		(11 "B.Adhes" user "B.Adhesive")
		(13 "F.Paste" user "Package Geometry/Pastemask Top")
		(15 "B.Paste" user "Package Geometry/Pastemask Bottom")
		(5 "F.SilkS" user "Ref Des/Silkscreen Top")
		(7 "B.SilkS" user "Ref Des/Silkscreen Bottom")
		(1 "F.Mask" user "Board Geometry/Soldermask Top")
		(3 "B.Mask" user "Board Geometry/Soldermask Bottom")
		(17 "Dwgs.User" user "User.Drawings")
		(19 "Cmts.User" user "User.Comments")
		(21 "Eco1.User" user "User.Eco1")
		(23 "Eco2.User" user "User.Eco2")
		(25 "Edge.Cuts" user "Board Geometry/Outline")
		(27 "Margin" user)
		(31 "F.CrtYd" user "Package Geometry/Place Bound Top")
		(29 "B.CrtYd" user "Package Geometry/Place Bound Bottom")
		(35 "F.Fab" user "Ref Des/Assembly Top")
		(33 "B.Fab" user "Ref Des/Assembly Bottom")
	)
	(footprint ""
		(layer "B.Cu")
		(at 325.193914 -62.004956 -90)
		(property "Reference" "R1675"
			(at 0 0 90)
			(layer "B.SilkS")
			(hide yes)
			(effects
				(font
					(size 1.27 1.27)
				)
				(justify mirror)
			)
		)
		(property "Value" ""
			(at 0 0 90)
			(layer "B.Fab")
			(effects
				(font
					(size 1.27 1.27)
				)
				(justify mirror)
			)
		)
		(duplicate_pad_numbers_are_jumpers no)
		(fp_line
			(start -0.7874 0.4064)
			(end 0.7874 0.4064)
			(stroke
				(width 0.1524)
				(type default)
			)
			(layer "B.SilkS")
		)
		(fp_line
			(start 0.7874 0.4064)
			(end 0.7874 -0.4064)
			(stroke
				(width 0.1524)
				(type default)
			)
			(layer "B.SilkS")
		)
		(fp_line
			(start -0.7874 -0.4064)
			(end -0.7874 0.4064)
			(stroke
				(width 0.1524)
				(type default)
			)
			(layer "B.SilkS")
		)
		(fp_line
			(start 0.7874 -0.4064)
			(end -0.7874 -0.4064)
			(stroke
				(width 0.1524)
				(type default)
			)
			(layer "B.SilkS")
		)
		(fp_line
			(start -0.67945 0.3048)
			(end -0.120396 0.3048)
			(stroke
				(width 0.1)
				(type default)
			)
			(layer "B.Fab")
		)
		(fp_line
			(start -0.120396 0.3048)
			(end -0.120396 0.2794)
			(stroke
				(width 0.1)
				(type default)
			)
			(layer "B.Fab")
		)
		(fp_line
			(start 0.12065 0.3048)
			(end 0.67945 0.3048)
			(stroke
				(width 0.1)
				(type default)
			)
			(layer "B.Fab")
		)
		(fp_line
			(start 0.67945 0.3048)
			(end 0.67945 -0.305054)
			(stroke
				(width 0.1)
				(type default)
			)
			(layer "B.Fab")
		)
		(fp_line
			(start -0.120396 0.2794)
			(end 0.12065 0.2794)
			(stroke
				(width 0.1)
				(type default)
			)
			(layer "B.Fab")
		)
		(fp_line
			(start 0.12065 0.2794)
			(end 0.12065 0.3048)
			(stroke
				(width 0.1)
				(type default)
			)
			(layer "B.Fab")
		)
		(fp_line
			(start -0.12065 -0.2794)
			(end -0.12065 -0.3048)
			(stroke
				(width 0.1)
				(type default)
			)
			(layer "B.Fab")
		)
		(fp_line
			(start 0.12065 -0.2794)
			(end -0.12065 -0.2794)
			(stroke
				(width 0.1)
				(type default)
			)
			(layer "B.Fab")
		)
		(fp_line
			(start -0.67945 -0.3048)
			(end -0.67945 0.3048)
			(stroke
				(width 0.1)
				(type default)
			)
			(layer "B.Fab")
		)
		(fp_line
			(start -0.12065 -0.3048)
			(end -0.67945 -0.3048)
			(stroke
				(width 0.1)
				(type default)
			)
			(layer "B.Fab")
		)
		(fp_line
			(start 0.12065 -0.305054)
			(end 0.12065 -0.2794)
			(stroke
				(width 0.1)
				(type default)
			)
			(layer "B.Fab")
		)
		(fp_line
			(start 0.67945 -0.305054)
			(end 0.12065 -0.305054)
			(stroke
				(width 0.1)
				(type default)
			)
			(layer "B.Fab")
		)
		(pad "1" smd circle
			(at 0.40005 0 90)
			(size 0 0)
			(layers "B.Cu" "B.Mask" "B.Paste")
			(net "FM_PCIE_EV_BIF_EN")
		)
		(pad "2" smd circle
			(at -0.40005 0 90)
			(size 0 0)
			(layers "B.Cu" "B.Mask" "B.Paste")
			(net "P3V3_AUX")
		)
	)
	(footprint ""
		(layer "B.Cu")
		(at 47.650908 -193.25971 -90)
		(property "Reference" "R257"
			(at 0 0 90)
			(layer "B.SilkS")
			(hide yes)
			(effects
				(font
					(size 1.27 1.27)
				)
				(justify mirror)
			)
		)
		(property "Value" ""
			(at 0 0 90)
			(layer "B.Fab")
			(effects
				(font
					(size 1.27 1.27)
				)
				(justify mirror)
			)
		)
		(duplicate_pad_numbers_are_jumpers no)
		(fp_line
			(start -0.7874 0.4064)
			(end 0.7874 0.4064)
			(stroke
				(width 0.1524)
				(type default)
			)
			(layer "B.SilkS")
		)
		(fp_line
			(start 0.7874 0.4064)
			(end 0.7874 -0.4064)
			(stroke
				(width 0.1524)
				(type default)
			)
			(layer "B.SilkS")
		)
		(fp_line
			(start -0.7874 -0.4064)
			(end -0.7874 0.4064)
			(stroke
				(width 0.1524)
				(type default)
			)
			(layer "B.SilkS")
		)
		(fp_line
			(start 0.7874 -0.4064)
			(end -0.7874 -0.4064)
			(stroke
				(width 0.1524)
				(type default)
			)
			(layer "B.SilkS")
		)
		(fp_line
			(start -0.67945 0.3048)
			(end -0.120396 0.3048)
			(stroke
				(width 0.1)
				(type default)
			)
			(layer "B.Fab")
		)
		(fp_line
			(start -0.120396 0.3048)
			(end -0.120396 0.2794)
			(stroke
				(width 0.1)
				(type default)
			)
			(layer "B.Fab")
		)
		(fp_line
			(start 0.12065 0.3048)
			(end 0.67945 0.3048)
			(stroke
				(width 0.1)
				(type default)
			)
			(layer "B.Fab")
		)
		(fp_line
			(start 0.67945 0.3048)
			(end 0.67945 -0.305054)
			(stroke
				(width 0.1)
				(type default)
			)
			(layer "B.Fab")
		)
		(fp_line
			(start -0.120396 0.2794)
			(end 0.12065 0.2794)
			(stroke
				(width 0.1)
				(type default)
			)
			(layer "B.Fab")
		)
		(fp_line
			(start 0.12065 0.2794)
			(end 0.12065 0.3048)
			(stroke
				(width 0.1)
				(type default)
			)
			(layer "B.Fab")
		)
		(fp_line
			(start -0.12065 -0.2794)
			(end -0.12065 -0.3048)
			(stroke
				(width 0.1)
				(type default)
			)
			(layer "B.Fab")
		)
		(fp_line
			(start 0.12065 -0.2794)
			(end -0.12065 -0.2794)
			(stroke
				(width 0.1)
				(type default)
			)
			(layer "B.Fab")
		)
		(fp_line
			(start -0.67945 -0.3048)
			(end -0.67945 0.3048)
			(stroke
				(width 0.1)
				(type default)
			)
			(layer "B.Fab")
		)
		(fp_line
			(start -0.12065 -0.3048)
			(end -0.67945 -0.3048)
			(stroke
				(width 0.1)
				(type default)
			)
			(layer "B.Fab")
		)
		(fp_line
			(start 0.12065 -0.305054)
			(end 0.12065 -0.2794)
			(stroke
				(width 0.1)
				(type default)
			)
			(layer "B.Fab")
		)
		(fp_line
			(start 0.67945 -0.305054)
			(end 0.12065 -0.305054)
			(stroke
				(width 0.1)
				(type default)
			)
			(layer "B.Fab")
		)
		(pad "1" smd circle
			(at 0.40005 0 90)
			(size 0 0)
			(layers "B.Cu" "B.Mask" "B.Paste")
			(net "PVNN_TERM_CPU1")
		)
		(pad "2" smd circle
			(at -0.40005 0 90)
			(size 0 0)
			(layers "B.Cu" "B.Mask" "B.Paste")
			(net "FM_S3M_CPU1_LVC1_GPIO_4")
		)
	)
	(footprint ""
		(layer "B.Cu")
		(at 338.133182 -64.315848 90)
		(property "Reference" "C170"
			(at 0 0 90)
			(layer "B.SilkS")
			(hide yes)
			(effects
				(font
					(size 1.27 1.27)
				)
				(justify mirror)
			)
		)
		(property "Value" ""
			(at 0 0 90)
			(layer "B.Fab")
			(effects
				(font
					(size 1.27 1.27)
				)
				(justify mirror)
			)
		)
		(duplicate_pad_numbers_are_jumpers no)
		(fp_line
			(start 0.299974 -0.150114)
			(end -0.299974 -0.150114)
			(stroke
				(width 0.1)
				(type default)
			)
			(layer "B.Fab")
		)
		(fp_line
			(start -0.299974 -0.150114)
			(end -0.299974 0.150114)
			(stroke
				(width 0.1)
				(type default)
			)
			(layer "B.Fab")
		)
		(fp_line
			(start 0.299974 0.150114)
			(end 0.299974 -0.150114)
			(stroke
				(width 0.1)
				(type default)
			)
			(layer "B.Fab")
		)
		(fp_line
			(start -0.299974 0.150114)
			(end 0.299974 0.150114)
			(stroke
				(width 0.1)
				(type default)
			)
			(layer "B.Fab")
		)
		(pad "1" smd rect
			(at 0.2667 0 270)
			(size 0.3048 0.381)
			(layers "B.Cu" "B.Mask" "B.Paste")
			(net "DMI_CPU0_PCH_RX_C_DP<0>")
		)
		(pad "2" smd rect
			(at -0.2667 0 270)
			(size 0.3048 0.381)
			(layers "B.Cu" "B.Mask" "B.Paste")
			(net "DMI_CPU0_PCH_RX_DP<0>")
		)
	)
)
